(kicad_pcb
	(version 20241229)
	(generator "pcbnew")
	(generator_version "9.0")
	(general
		(thickness 1.61)
		(legacy_teardrops no)
	)
	(paper "A3")
	(title_block
		(title "RDIMM DDR5 Tester")
		(date "2026-05-21")
		(rev "2.2.0")
		(company "Antmicro")
		(comment 9 "footprints 328-331 of 796")
	)
	(layers
		(0 "F.Cu" signal)
		(4 "In1.Cu" power)
		(6 "In2.Cu" mixed)
		(8 "In3.Cu" power)
		(10 "In4.Cu" mixed)
		(12 "In5.Cu" power)
		(14 "In6.Cu" mixed)
		(16 "In7.Cu" power)
		(18 "In8.Cu" power)
		(20 "In9.Cu" mixed)
		(22 "In10.Cu" power)
		(2 "B.Cu" signal)
		(9 "F.Adhes" user "F.Adhesive")
		(11 "B.Adhes" user "B.Adhesive")
		(13 "F.Paste" user)
		(15 "B.Paste" user)
		(5 "F.SilkS" user "F.Silkscreen")
		(7 "B.SilkS" user "B.Silkscreen")
		(1 "F.Mask" user)
		(3 "B.Mask" user)
		(17 "Dwgs.User" user "User.Drawings")
		(19 "Cmts.User" user "User.Comments")
		(21 "Eco1.User" user "User.Eco1")
		(23 "Eco2.User" user "User.Eco2")
		(25 "Edge.Cuts" user)
		(27 "Margin" user)
		(31 "F.CrtYd" user "F.Courtyard")
		(29 "B.CrtYd" user "B.Courtyard")
		(35 "F.Fab" user)
		(33 "B.Fab" user)
	)
	(footprint "antmicro-footprints:R_0603_1608Metric"
		(layer "F.Cu")
		(at 230.45 167.95 90)
		(descr "Resistor SMD 0603")
		(tags "resistor SMD 0603")
		(property "Reference" "R211"
			(at 1.2 0.55 90)
			(layer "F.SilkS")
			(effects
				(font
					(size 0.7 0.7)
					(thickness 0.15)
				)
				(justify left bottom)
			)
		)
		(property "Value" "R_0R_22.4A_0603"
			(at 0 1.6 90)
			(layer "F.Fab")
			(effects
				(font
					(size 0.7 0.7)
					(thickness 0.15)
				)
				(justify left bottom)
			)
		)
		(property "Datasheet" "https://fscdn.rohm.com/en/products/databook/datasheet/passive/resistor/chip_resistor/pmr-jpw-e.pdf"
			(at 0 0 90)
			(layer "F.Fab")
			(hide yes)
			(effects
				(font
					(size 1.27 1.27)
					(thickness 0.15)
				)
			)
		)
		(property "Manufacturer" "ROHM Semiconductor"
			(at 0 0 90)
			(unlocked yes)
			(layer "F.Fab")
			(hide yes)
			(effects
				(font
					(size 1 1)
					(thickness 0.15)
				)
			)
		)
		(property "MPN" "PMR03EZPJ000"
			(at 0 0 90)
			(unlocked yes)
			(layer "F.Fab")
			(hide yes)
			(effects
				(font
					(size 1 1)
					(thickness 0.15)
				)
			)
		)
		(property "Val" "0R"
			(at 0 0 90)
			(unlocked yes)
			(layer "F.Fab")
			(hide yes)
			(effects
				(font
					(size 1 1)
					(thickness 0.15)
				)
			)
		)
		(property "Author" "Antmicro"
			(at 0 0 90)
			(unlocked yes)
			(layer "F.Fab")
			(hide yes)
			(effects
				(font
					(size 1 1)
					(thickness 0.15)
				)
			)
		)
		(property "License" "Apache-2.0"
			(at 0 0 90)
			(unlocked yes)
			(layer "F.Fab")
			(hide yes)
			(effects
				(font
					(size 1 1)
					(thickness 0.15)
				)
			)
		)
		(property "Max. Curr." "22.4A"
			(at 0 0 90)
			(unlocked yes)
			(layer "F.Fab")
			(hide yes)
			(effects
				(font
					(size 1 1)
					(thickness 0.15)
				)
			)
		)
		(sheetname "/Supply/DC-DC VCCINT/")
		(sheetfile "dc-dc-vccint.kicad_sch")
		(attr smd)
		(fp_line
			(start -0.15 -0.4)
			(end 0.15 -0.4)
			(stroke
				(width 0.15)
				(type solid)
			)
			(layer "F.SilkS")
		)
		(fp_line
			(start -0.15 0.4)
			(end 0.15 0.4)
			(stroke
				(width 0.15)
				(type solid)
			)
			(layer "F.SilkS")
		)
		(fp_rect
			(start -1.25 -0.65)
			(end 1.25 0.65)
			(stroke
				(width 0.05)
				(type solid)
			)
			(fill no)
			(layer "F.CrtYd")
		)
		(fp_rect
			(start -0.8 -0.4)
			(end 0.8 0.4)
			(stroke
				(width 0.15)
				(type solid)
			)
			(fill no)
			(layer "F.Fab")
		)
		(fp_text user "License: Apache-2.0"
			(at -1.25 5.9 90)
			(layer "F.Fab")
			(effects
				(font
					(size 0.7 0.7)
					(thickness 0.15)
				)
				(justify left bottom)
			)
		)
		(fp_text user "${REFERENCE}"
			(at -1.25 3.898 90)
			(layer "F.Fab")
			(effects
				(font
					(size 0.7 0.7)
					(thickness 0.15)
				)
				(justify left bottom)
			)
		)
		(fp_text user "Author: Antmicro"
			(at -1.25 4.9 90)
			(layer "F.Fab")
			(effects
				(font
					(size 0.7 0.7)
					(thickness 0.15)
				)
				(justify left bottom)
			)
		)
		(pad "1" smd roundrect
			(at -0.7 0 90)
			(size 0.8 1)
			(layers "F.Cu" "F.Mask" "F.Paste")
			(roundrect_rratio 0.2)
			(net 224 "/Supply/DC-DC VCCINT/0V85_REG1")
			(pintype "passive")
		)
		(pad "2" smd roundrect
			(at 0.7 0 90)
			(size 0.8 1)
			(layers "F.Cu" "F.Mask" "F.Paste")
			(roundrect_rratio 0.2)
			(net 553 "+0V85")
			(pintype "passive")
		)
	)
	(footprint "antmicro-footprints:TP_SMD_1mm"
		(layer "F.Cu")
		(at 244.025 165.825)
		(property "Reference" "TP15"
			(at 0 -0.731898 0)
			(layer "F.SilkS")
			(hide yes)
			(effects
				(font
					(size 0.7 0.7)
					(thickness 0.15)
				)
				(justify left bottom)
			)
		)
		(property "Value" "TP_1mm_SMD"
			(at 0 1.4 0)
			(layer "F.Fab")
			(effects
				(font
					(size 0.7 0.7)
					(thickness 0.15)
				)
				(justify left bottom)
			)
		)
		(property "MPN" ""
			(at 0 0 0)
			(unlocked yes)
			(layer "F.Fab")
			(hide yes)
			(effects
				(font
					(size 1 1)
					(thickness 0.15)
				)
			)
		)
		(property "Manufacturer" ""
			(at 0 0 0)
			(unlocked yes)
			(layer "F.Fab")
			(hide yes)
			(effects
				(font
					(size 1 1)
					(thickness 0.15)
				)
			)
		)
		(property "Author" "Antmicro"
			(at 0 0 0)
			(unlocked yes)
			(layer "F.Fab")
			(hide yes)
			(effects
				(font
					(size 1 1)
					(thickness 0.15)
				)
			)
		)
		(property "License" "Apache-2.0"
			(at 0 0 0)
			(unlocked yes)
			(layer "F.Fab")
			(hide yes)
			(effects
				(font
					(size 1 1)
					(thickness 0.15)
				)
			)
		)
		(sheetname "/Supply/DC-DC AUX, MGT/")
		(sheetfile "dc-dc-aux-mgt.kicad_sch")
		(attr exclude_from_pos_files)
		(fp_circle
			(center 0 0)
			(end 0.6 0)
			(stroke
				(width 0.05)
				(type default)
			)
			(fill no)
			(layer "F.CrtYd")
		)
		(fp_text user "License: Apache-2.0"
			(at -0.5 5.2 0)
			(layer "F.Fab")
			(effects
				(font
					(size 0.7 0.7)
					(thickness 0.15)
				)
				(justify left bottom)
			)
		)
		(fp_text user "${REFERENCE}"
			(at -0.5 2.8 0)
			(layer "F.Fab")
			(effects
				(font
					(size 0.7 0.7)
					(thickness 0.15)
				)
				(justify left bottom)
			)
		)
		(fp_text user "Author: Antmicro"
			(at -0.5 4 0)
			(layer "F.Fab")
			(effects
				(font
					(size 0.7 0.7)
					(thickness 0.15)
				)
				(justify left bottom)
			)
		)
		(pad "1" smd circle
			(at 0 0)
			(size 1 1)
			(layers "F.Cu" "F.Mask")
			(net 820 "+0V9_MGTAVCC")
			(pinfunction "1")
			(pintype "passive")
		)
	)
	(footprint "antmicro-footprints:FBGA-25-24_6x8mm_Layout5x5_P1mm"
		(layer "F.Cu")
		(at 167.1 152.5 -90)
		(property "Reference" "U1"
			(at 0 -4.5 90)
			(layer "F.SilkS")
			(effects
				(font
					(size 0.7 0.7)
					(thickness 0.15)
				)
				(justify right bottom)
			)
		)
		(property "Value" "IS66WVH16M8DALL-166B1LI"
			(at 0.1 5.3 90)
			(layer "F.Fab")
			(effects
				(font
					(size 0.7 0.7)
					(thickness 0.15)
				)
				(justify right bottom)
			)
		)
		(property "Datasheet" "https://www.issi.com/WW/pdf/66-67WVH16M8DALL-BLL.pdf"
			(at 0 0 270)
			(layer "F.Fab")
			(hide yes)
			(effects
				(font
					(size 1.27 1.27)
					(thickness 0.15)
				)
			)
		)
		(property "Manufacturer" "ISSI"
			(at 0 0 270)
			(unlocked yes)
			(layer "F.Fab")
			(hide yes)
			(effects
				(font
					(size 1 1)
					(thickness 0.15)
				)
			)
		)
		(property "MPN" "IS66WVH16M8DALL-166B1LI"
			(at 0 0 270)
			(unlocked yes)
			(layer "F.Fab")
			(hide yes)
			(effects
				(font
					(size 1 1)
					(thickness 0.15)
				)
			)
		)
		(property "Author" "Antmicro"
			(at 0 0 270)
			(unlocked yes)
			(layer "F.Fab")
			(hide yes)
			(effects
				(font
					(size 1 1)
					(thickness 0.15)
				)
			)
		)
		(property "License" "Apache-2.0"
			(at 0 0 270)
			(unlocked yes)
			(layer "F.Fab")
			(hide yes)
			(effects
				(font
					(size 1 1)
					(thickness 0.15)
				)
			)
		)
		(sheetname "/HyperRAM + QSPI Flash/")
		(sheetfile "hyperram-flash.kicad_sch")
		(attr smd)
		(fp_line
			(start -3.121 4.12)
			(end -3.121 2.12)
			(stroke
				(width 0.15)
				(type solid)
			)
			(layer "F.SilkS")
		)
		(fp_line
			(start -1.621 4.12)
			(end -3.121 4.12)
			(stroke
				(width 0.15)
				(type solid)
			)
			(layer "F.SilkS")
		)
		(fp_line
			(start 1.62 4.12)
			(end 3.12 4.12)
			(stroke
				(width 0.15)
				(type solid)
			)
			(layer "F.SilkS")
		)
		(fp_line
			(start 3.12 4.12)
			(end 3.12 2.12)
			(stroke
				(width 0.15)
				(type solid)
			)
			(layer "F.SilkS")
		)
		(fp_line
			(start -3.121 -3)
			(end -3.121 -2.121)
			(stroke
				(width 0.15)
				(type solid)
			)
			(layer "F.SilkS")
		)
		(fp_line
			(start -2 -4.121)
			(end -3.121 -3)
			(stroke
				(width 0.15)
				(type solid)
			)
			(layer "F.SilkS")
		)
		(fp_line
			(start -1.621 -4.121)
			(end -2 -4.121)
			(stroke
				(width 0.15)
				(type solid)
			)
			(layer "F.SilkS")
		)
		(fp_line
			(start 1.62 -4.121)
			(end 3.12 -4.121)
			(stroke
				(width 0.15)
				(type solid)
			)
			(layer "F.SilkS")
		)
		(fp_line
			(start 1.62 -4.121)
			(end 3.12 -4.121)
			(stroke
				(width 0.15)
				(type solid)
			)
			(layer "F.SilkS")
		)
		(fp_line
			(start 1.62 -4.121)
			(end 3.12 -4.121)
			(stroke
				(width 0.15)
				(type solid)
			)
			(layer "F.SilkS")
		)
		(fp_line
			(start 3.12 -4.121)
			(end 3.12 -2.121)
			(stroke
				(width 0.15)
				(type solid)
			)
			(layer "F.SilkS")
		)
		(fp_line
			(start 3.12 -4.121)
			(end 3.12 -2.121)
			(stroke
				(width 0.15)
				(type solid)
			)
			(layer "F.SilkS")
		)
		(fp_line
			(start 3.12 -4.121)
			(end 3.12 -2.121)
			(stroke
				(width 0.15)
				(type solid)
			)
			(layer "F.SilkS")
		)
		(fp_circle
			(center -3.6 -3.9)
			(end -3.5 -3.9)
			(stroke
				(width 0.15)
				(type solid)
			)
			(fill yes)
			(layer "F.SilkS")
		)
		(fp_line
			(start -3.25 4.24)
			(end -3.25 -4.25)
			(stroke
				(width 0.05)
				(type solid)
			)
			(layer "F.CrtYd")
		)
		(fp_line
			(start 3.24 4.24)
			(end -3.25 4.24)
			(stroke
				(width 0.05)
				(type solid)
			)
			(layer "F.CrtYd")
		)
		(fp_line
			(start -3.25 -4.25)
			(end 3.24 -4.25)
			(stroke
				(width 0.05)
				(type solid)
			)
			(layer "F.CrtYd")
		)
		(fp_line
			(start 3.24 -4.25)
			(end 3.24 4.24)
			(stroke
				(width 0.05)
				(type solid)
			)
			(layer "F.CrtYd")
		)
		(fp_line
			(start -3 4)
			(end 3 4)
			(stroke
				(width 0.15)
				(type solid)
			)
			(layer "F.Fab")
		)
		(fp_line
			(start 3 4)
			(end 3 -4)
			(stroke
				(width 0.15)
				(type solid)
			)
			(layer "F.Fab")
		)
		(fp_line
			(start -3 -3)
			(end -3 4)
			(stroke
				(width 0.15)
				(type solid)
			)
			(layer "F.Fab")
		)
		(fp_line
			(start -2 -4)
			(end -3 -3)
			(stroke
				(width 0.15)
				(type solid)
			)
			(layer "F.Fab")
		)
		(fp_line
			(start 3 -4)
			(end -2 -4)
			(stroke
				(width 0.15)
				(type solid)
			)
			(layer "F.Fab")
		)
		(fp_text user "License: Apache-2.0"
			(at -3.25 10.759 270)
			(layer "F.Fab")
			(effects
				(font
					(size 0.7 0.7)
					(thickness 0.15)
				)
				(justify left bottom)
			)
		)
		(fp_text user "${REFERENCE}"
			(at -3.25 8.359 270)
			(layer "F.Fab")
			(effects
				(font
					(size 0.7 0.7)
					(thickness 0.15)
				)
				(justify left bottom)
			)
		)
		(fp_text user "Author: Antmicro"
			(at -3.25 9.559 270)
			(layer "F.Fab")
			(effects
				(font
					(size 0.7 0.7)
					(thickness 0.15)
				)
				(justify left bottom)
			)
		)
		(pad "A2" smd circle
			(at -1 -2 270)
			(size 0.4 0.4)
			(layers "F.Cu" "F.Mask" "F.Paste")
			(net 303 "unconnected-(U1-NC-PadA2)")
			(pinfunction "NC")
			(pintype "no_connect")
		)
		(pad "A3" smd circle
			(at 0 -2 270)
			(size 0.4 0.4)
			(layers "F.Cu" "F.Mask" "F.Paste")
			(net 618 "/FPGA banks HP/HyperRAM.~{CS}")
			(pinfunction "~{CS}")
			(pintype "input")
		)
		(pad "A4" smd circle
			(at 1 -2 270)
			(size 0.4 0.4)
			(layers "F.Cu" "F.Mask" "F.Paste")
			(net 623 "/FPGA banks HP/HyperRAM.~{RESET}")
			(pinfunction "~{RESET}")
			(pintype "input")
		)
		(pad "A5" smd circle
			(at 2 -2 270)
			(size 0.4 0.4)
			(layers "F.Cu" "F.Mask" "F.Paste")
			(net 304 "unconnected-(U1-NC-PadA5)")
			(pinfunction "NC")
			(pintype "no_connect")
		)
		(pad "B1" smd circle
			(at -2 -1 270)
			(size 0.4 0.4)
			(layers "F.Cu" "F.Mask" "F.Paste")
			(net 617 "/FPGA banks HP/HyperRAM.CK_N")
			(pinfunction "CK-")
			(pintype "input")
		)
		(pad "B2" smd circle
			(at -1 -1 270)
			(size 0.4 0.4)
			(layers "F.Cu" "F.Mask" "F.Paste")
			(net 616 "/FPGA banks HP/HyperRAM.CK_P")
			(pinfunction "CK+")
			(pintype "input")
		)
		(pad "B3" smd circle
			(at 0 -1 270)
			(size 0.4 0.4)
			(layers "F.Cu" "F.Mask" "F.Paste")
			(net 1 "GND")
			(pinfunction "VSS")
			(pintype "power_in")
		)
		(pad "B4" smd circle
			(at 1 -1 270)
			(size 0.4 0.4)
			(layers "F.Cu" "F.Mask" "F.Paste")
			(net 797 "+1V8")
			(pinfunction "VCC")
			(pintype "power_in")
		)
		(pad "B5" smd circle
			(at 2 -1 270)
			(size 0.4 0.4)
			(layers "F.Cu" "F.Mask" "F.Paste")
			(net 305 "unconnected-(U1-NC-PadB5)")
			(pinfunction "NC")
			(pintype "no_connect")
		)
		(pad "C1" smd circle
			(at -2 0 270)
			(size 0.4 0.4)
			(layers "F.Cu" "F.Mask" "F.Paste")
			(net 1 "GND")
			(pinfunction "VSSQ")
			(pintype "power_in")
		)
		(pad "C2" smd circle
			(at -1 0 270)
			(size 0.4 0.4)
			(layers "F.Cu" "F.Mask" "F.Paste")
			(net 306 "unconnected-(U1-NC-PadC2)")
			(pinfunction "NC")
			(pintype "no_connect")
		)
		(pad "C3" smd circle
			(at 0 0 270)
			(size 0.4 0.4)
			(layers "F.Cu" "F.Mask" "F.Paste")
			(net 624 "/FPGA banks HP/HyperRAM.RWDS")
			(pinfunction "RWDS")
			(pintype "bidirectional")
		)
		(pad "C4" smd circle
			(at 1 0 270)
			(size 0.4 0.4)
			(layers "F.Cu" "F.Mask" "F.Paste")
			(net 615 "/FPGA banks HP/HyperRAM.DQ2")
			(pinfunction "DQ2")
			(pintype "bidirectional")
		)
		(pad "C5" smd circle
			(at 2 0 270)
			(size 0.4 0.4)
			(layers "F.Cu" "F.Mask" "F.Paste")
			(net 307 "unconnected-(U1-NC-PadC5)")
			(pinfunction "NC")
			(pintype "no_connect")
		)
		(pad "D1" smd circle
			(at -2 1 270)
			(size 0.4 0.4)
			(layers "F.Cu" "F.Mask" "F.Paste")
			(net 797 "+1V8")
			(pinfunction "VCCQ")
			(pintype "power_in")
		)
		(pad "D2" smd circle
			(at -1 1 270)
			(size 0.4 0.4)
			(layers "F.Cu" "F.Mask" "F.Paste")
			(net 620 "/FPGA banks HP/HyperRAM.DQ1")
			(pinfunction "DQ1")
			(pintype "bidirectional")
		)
		(pad "D3" smd circle
			(at 0 1 270)
			(size 0.4 0.4)
			(layers "F.Cu" "F.Mask" "F.Paste")
			(net 622 "/FPGA banks HP/HyperRAM.DQ0")
			(pinfunction "DQ0")
			(pintype "bidirectional")
		)
		(pad "D4" smd circle
			(at 1 1 270)
			(size 0.4 0.4)
			(layers "F.Cu" "F.Mask" "F.Paste")
			(net 613 "/FPGA banks HP/HyperRAM.DQ3")
			(pinfunction "DQ3")
			(pintype "bidirectional")
		)
		(pad "D5" smd circle
			(at 2 1 270)
			(size 0.4 0.4)
			(layers "F.Cu" "F.Mask" "F.Paste")
			(net 621 "/FPGA banks HP/HyperRAM.DQ4")
			(pinfunction "DQ4")
			(pintype "bidirectional")
		)
		(pad "E1" smd circle
			(at -2 2 270)
			(size 0.4 0.4)
			(layers "F.Cu" "F.Mask" "F.Paste")
			(net 610 "/FPGA banks HP/HyperRAM.DQ7")
			(pinfunction "DQ7")
			(pintype "bidirectional")
		)
		(pad "E2" smd circle
			(at -1 2 270)
			(size 0.4 0.4)
			(layers "F.Cu" "F.Mask" "F.Paste")
			(net 614 "/FPGA banks HP/HyperRAM.DQ6")
			(pinfunction "DQ6")
			(pintype "bidirectional")
		)
		(pad "E3" smd circle
			(at 0 2 270)
			(size 0.4 0.4)
			(layers "F.Cu" "F.Mask" "F.Paste")
			(net 619 "/FPGA banks HP/HyperRAM.DQ5")
			(pinfunction "DQ5")
			(pintype "bidirectional")
		)
		(pad "E4" smd circle
			(at 1 2 270)
			(size 0.4 0.4)
			(layers "F.Cu" "F.Mask" "F.Paste")
			(net 797 "+1V8")
			(pinfunction "VCCQ")
			(pintype "passive")
		)
		(pad "E5" smd circle
			(at 2 2 270)
			(size 0.4 0.4)
			(layers "F.Cu" "F.Mask" "F.Paste")
			(net 1 "GND")
			(pinfunction "VSSQ")
			(pintype "passive")
		)
	)
	(footprint "antmicro-footprints:R_0402_1005Metric"
		(layer "F.Cu")
		(at 125.681 166.1125 90)
		(descr "Resistor SMD 0402")
		(tags "resistor SMD 0402")
		(property "Reference" "R226"
			(at 0.9125 3.969 90)
			(layer "F.SilkS")
			(effects
				(font
					(size 0.7 0.7)
					(thickness 0.15)
				)
				(justify left bottom)
			)
		)
		(property "Value" "R_64k9_0402"
			(at -1.011843 1.772047 90)
			(layer "F.Fab")
			(effects
				(font
					(size 0.7 0.7)
					(thickness 0.15)
				)
				(justify left bottom)
			)
		)
		(property "Datasheet" "https://www.bourns.com/docs/product-datasheets/cr.pdf"
			(at 0 0 90)
			(layer "F.Fab")
			(hide yes)
			(effects
				(font
					(size 1.27 1.27)
					(thickness 0.15)
				)
			)
		)
		(property "MPN" "CR0402-FX-6492GLF"
			(at 0 0 90)
			(unlocked yes)
			(layer "F.Fab")
			(hide yes)
			(effects
				(font
					(size 1 1)
					(thickness 0.15)
				)
			)
		)
		(property "Manufacturer" "Bourns"
			(at 0 0 90)
			(unlocked yes)
			(layer "F.Fab")
			(hide yes)
			(effects
				(font
					(size 1 1)
					(thickness 0.15)
				)
			)
		)
		(property "License" "Apache-2.0"
			(at 0 0 90)
			(unlocked yes)
			(layer "F.Fab")
			(hide yes)
			(effects
				(font
					(size 1 1)
					(thickness 0.15)
				)
			)
		)
		(property "Author" "Antmicro"
			(at 0 0 90)
			(unlocked yes)
			(layer "F.Fab")
			(hide yes)
			(effects
				(font
					(size 1 1)
					(thickness 0.15)
				)
			)
		)
		(property "Val" "64k9"
			(at 0 0 90)
			(unlocked yes)
			(layer "F.Fab")
			(hide yes)
			(effects
				(font
					(size 1 1)
					(thickness 0.15)
				)
			)
		)
		(property "Tolerance" "1%"
			(at 0 0 90)
			(unlocked yes)
			(layer "F.Fab")
			(hide yes)
			(effects
				(font
					(size 1 1)
					(thickness 0.15)
				)
			)
		)
		(sheetname "/HDMI + SD Card/")
		(sheetfile "hdmi-sd-card.kicad_sch")
		(attr smd exclude_from_bom dnp)
		(fp_rect
			(start -0.925 -0.47)
			(end 0.925 0.47)
			(stroke
				(width 0.05)
				(type default)
			)
			(fill no)
			(layer "F.CrtYd")
		)
		(fp_rect
			(start -0.5 -0.25)
			(end 0.5 0.25)
			(stroke
				(width 0.15)
				(type solid)
			)
			(fill no)
			(layer "F.Fab")
		)
		(fp_text user "Author: Antmicro"
			(at -0.95 4.169 90)
			(layer "F.Fab")
			(effects
				(font
					(size 0.7 0.7)
					(thickness 0.15)
				)
				(justify left bottom)
			)
		)
		(fp_text user "${REFERENCE}"
			(at -0.95 3.168 90)
			(layer "F.Fab")
			(effects
				(font
					(size 0.7 0.7)
					(thickness 0.15)
				)
				(justify left bottom)
			)
		)
		(fp_text user "License: Apache-2.0"
			(at -0.95 5.169 90)
			(layer "F.Fab")
			(effects
				(font
					(size 0.7 0.7)
					(thickness 0.15)
				)
				(justify left bottom)
			)
		)
		(pad "1" smd roundrect
			(at -0.48 0 90)
			(size 0.59 0.64)
			(layers "F.Cu" "F.Mask" "F.Paste")
			(roundrect_rratio 0.25)
			(net 736 "/HDMI + SD Card/PRE_SEL")
			(pintype "passive")
		)
		(pad "2" smd roundrect
			(at 0.48 0 90)
			(size 0.59 0.64)
			(layers "F.Cu" "F.Mask" "F.Paste")
			(roundrect_rratio 0.25)
			(net 151 "+3V3")
			(pintype "passive")
		)
	)
)
